(kicad_pcb
	(version 20241229)
	(generator "pcbnew")
	(generator_version "9.0")
	(general
		(thickness 1.61)
		(legacy_teardrops no)
	)
	(paper "A3")
	(title_block
		(title "RDIMM DDR5 Tester")
		(date "2026-05-21")
		(rev "2.2.0")
		(company "Antmicro")
		(comment 9 "footprints 418-423 of 796")
	)
	(layers
		(0 "F.Cu" signal)
		(4 "In1.Cu" power)
		(6 "In2.Cu" mixed)
		(8 "In3.Cu" power)
		(10 "In4.Cu" mixed)
		(12 "In5.Cu" power)
		(14 "In6.Cu" mixed)
		(16 "In7.Cu" power)
		(18 "In8.Cu" power)
		(20 "In9.Cu" mixed)
		(22 "In10.Cu" power)
		(2 "B.Cu" signal)
		(9 "F.Adhes" user "F.Adhesive")
		(11 "B.Adhes" user "B.Adhesive")
		(13 "F.Paste" user)
		(15 "B.Paste" user)
		(5 "F.SilkS" user "F.Silkscreen")
		(7 "B.SilkS" user "B.Silkscreen")
		(1 "F.Mask" user)
		(3 "B.Mask" user)
		(17 "Dwgs.User" user "User.Drawings")
		(19 "Cmts.User" user "User.Comments")
		(21 "Eco1.User" user "User.Eco1")
		(23 "Eco2.User" user "User.Eco2")
		(25 "Edge.Cuts" user)
		(27 "Margin" user)
		(31 "F.CrtYd" user "F.Courtyard")
		(29 "B.CrtYd" user "B.Courtyard")
		(35 "F.Fab" user)
		(33 "B.Fab" user)
	)
	(footprint "antmicro-footprints:R_0402_1005Metric"
		(layer "B.Cu")
		(at 141.675 152.4 -90)
		(descr "Resistor SMD 0402")
		(tags "resistor SMD 0402")
		(property "Reference" "R118"
			(at 8 -0.375 90)
			(layer "B.SilkS")
			(effects
				(font
					(size 0.7 0.7)
					(thickness 0.15)
				)
				(justify left bottom mirror)
			)
		)
		(property "Value" "R_2k2_0402"
			(at -1.011843 -1.772047 90)
			(layer "B.Fab")
			(effects
				(font
					(size 0.7 0.7)
					(thickness 0.15)
				)
				(justify left bottom mirror)
			)
		)
		(property "Datasheet" "https://www.bourns.com/docs/product-datasheets/cr.pdf"
			(at 0 0 270)
			(layer "F.Fab")
			(hide yes)
			(effects
				(font
					(size 1.27 1.27)
					(thickness 0.15)
				)
			)
		)
		(property "Manufacturer" "Bourns"
			(at 0 0 270)
			(unlocked yes)
			(layer "B.Fab")
			(hide yes)
			(effects
				(font
					(size 1 1)
					(thickness 0.15)
				)
				(justify mirror)
			)
		)
		(property "MPN" "CR0402-FX-2201GLF"
			(at 0 0 270)
			(unlocked yes)
			(layer "B.Fab")
			(hide yes)
			(effects
				(font
					(size 1 1)
					(thickness 0.15)
				)
				(justify mirror)
			)
		)
		(property "Val" "2k2"
			(at 0 0 270)
			(unlocked yes)
			(layer "B.Fab")
			(hide yes)
			(effects
				(font
					(size 1 1)
					(thickness 0.15)
				)
				(justify mirror)
			)
		)
		(property "License" "Apache-2.0"
			(at 0 0 270)
			(unlocked yes)
			(layer "B.Fab")
			(hide yes)
			(effects
				(font
					(size 1 1)
					(thickness 0.15)
				)
				(justify mirror)
			)
		)
		(property "Author" "Antmicro"
			(at 0 0 270)
			(unlocked yes)
			(layer "B.Fab")
			(hide yes)
			(effects
				(font
					(size 1 1)
					(thickness 0.15)
				)
				(justify mirror)
			)
		)
		(property "Tolerance" "1%"
			(at 0 0 270)
			(unlocked yes)
			(layer "B.Fab")
			(hide yes)
			(effects
				(font
					(size 1 1)
					(thickness 0.15)
				)
				(justify mirror)
			)
		)
		(sheetname "/Ethernet/")
		(sheetfile "ethernet.kicad_sch")
		(attr smd)
		(fp_rect
			(start -0.925 0.47)
			(end 0.925 -0.47)
			(stroke
				(width 0.05)
				(type default)
			)
			(fill no)
			(layer "B.CrtYd")
		)
		(fp_rect
			(start -0.5 0.25)
			(end 0.5 -0.25)
			(stroke
				(width 0.15)
				(type solid)
			)
			(fill no)
			(layer "B.Fab")
		)
		(fp_text user "${REFERENCE}"
			(at -0.95 -3.168 90)
			(layer "B.Fab")
			(effects
				(font
					(size 0.7 0.7)
					(thickness 0.15)
				)
				(justify left bottom mirror)
			)
		)
		(fp_text user "Author: Antmicro"
			(at -0.95 -4.169 90)
			(layer "B.Fab")
			(effects
				(font
					(size 0.7 0.7)
					(thickness 0.15)
				)
				(justify left bottom mirror)
			)
		)
		(fp_text user "License: Apache-2.0"
			(at -0.95 -5.169 90)
			(layer "B.Fab")
			(effects
				(font
					(size 0.7 0.7)
					(thickness 0.15)
				)
				(justify left bottom mirror)
			)
		)
		(pad "1" smd roundrect
			(at -0.48 0 270)
			(size 0.59 0.64)
			(layers "B.Cu" "B.Mask" "B.Paste")
			(roundrect_rratio 0.25)
			(net 398 "/Ethernet/ETH.RXC")
			(pintype "passive")
		)
		(pad "2" smd roundrect
			(at 0.48 0 270)
			(size 0.59 0.64)
			(layers "B.Cu" "B.Mask" "B.Paste")
			(roundrect_rratio 0.25)
			(net 1 "GND")
			(pintype "passive")
		)
	)
	(footprint "antmicro-footprints:R_0402_1005Metric"
		(layer "B.Cu")
		(at 135.383171 143.399 90)
		(descr "Resistor SMD 0402")
		(tags "resistor SMD 0402")
		(property "Reference" "R119"
			(at -1.701 -3.603171 90)
			(layer "B.SilkS")
			(hide yes)
			(effects
				(font
					(size 0.7 0.7)
					(thickness 0.15)
				)
				(justify right bottom mirror)
			)
		)
		(property "Value" "R_2k2_0402"
			(at -1.011843 -1.772047 90)
			(layer "B.Fab")
			(effects
				(font
					(size 0.7 0.7)
					(thickness 0.15)
				)
				(justify right bottom mirror)
			)
		)
		(property "Datasheet" "https://www.bourns.com/docs/product-datasheets/cr.pdf"
			(at 0 0 90)
			(layer "F.Fab")
			(hide yes)
			(effects
				(font
					(size 1.27 1.27)
					(thickness 0.15)
				)
			)
		)
		(property "Manufacturer" "Bourns"
			(at 0 0 90)
			(unlocked yes)
			(layer "B.Fab")
			(hide yes)
			(effects
				(font
					(size 1 1)
					(thickness 0.15)
				)
				(justify mirror)
			)
		)
		(property "MPN" "CR0402-FX-2201GLF"
			(at 0 0 90)
			(unlocked yes)
			(layer "B.Fab")
			(hide yes)
			(effects
				(font
					(size 1 1)
					(thickness 0.15)
				)
				(justify mirror)
			)
		)
		(property "Val" "2k2"
			(at 0 0 90)
			(unlocked yes)
			(layer "B.Fab")
			(hide yes)
			(effects
				(font
					(size 1 1)
					(thickness 0.15)
				)
				(justify mirror)
			)
		)
		(property "License" "Apache-2.0"
			(at 0 0 90)
			(unlocked yes)
			(layer "B.Fab")
			(hide yes)
			(effects
				(font
					(size 1 1)
					(thickness 0.15)
				)
				(justify mirror)
			)
		)
		(property "Author" "Antmicro"
			(at 0 0 90)
			(unlocked yes)
			(layer "B.Fab")
			(hide yes)
			(effects
				(font
					(size 1 1)
					(thickness 0.15)
				)
				(justify mirror)
			)
		)
		(property "Tolerance" "1%"
			(at 0 0 90)
			(unlocked yes)
			(layer "B.Fab")
			(hide yes)
			(effects
				(font
					(size 1 1)
					(thickness 0.15)
				)
				(justify mirror)
			)
		)
		(sheetname "/Ethernet/")
		(sheetfile "ethernet.kicad_sch")
		(attr smd exclude_from_bom dnp)
		(fp_rect
			(start -0.925 0.47)
			(end 0.925 -0.47)
			(stroke
				(width 0.05)
				(type default)
			)
			(fill no)
			(layer "B.CrtYd")
		)
		(fp_rect
			(start -0.5 0.25)
			(end 0.5 -0.25)
			(stroke
				(width 0.15)
				(type solid)
			)
			(fill no)
			(layer "B.Fab")
		)
		(fp_text user "Author: Antmicro"
			(at -0.95 -4.169 270)
			(layer "B.Fab")
			(effects
				(font
					(size 0.7 0.7)
					(thickness 0.15)
				)
				(justify left bottom mirror)
			)
		)
		(fp_text user "License: Apache-2.0"
			(at -0.95 -5.169 270)
			(layer "B.Fab")
			(effects
				(font
					(size 0.7 0.7)
					(thickness 0.15)
				)
				(justify left bottom mirror)
			)
		)
		(fp_text user "${REFERENCE}"
			(at -0.95 -3.168 270)
			(layer "B.Fab")
			(effects
				(font
					(size 0.7 0.7)
					(thickness 0.15)
				)
				(justify left bottom mirror)
			)
		)
		(pad "1" smd roundrect
			(at -0.48 0 90)
			(size 0.59 0.64)
			(layers "B.Cu" "B.Mask" "B.Paste")
			(roundrect_rratio 0.25)
			(net 399 "/Ethernet/ETH.REF_CLK")
			(pintype "passive")
		)
		(pad "2" smd roundrect
			(at 0.48 0 90)
			(size 0.59 0.64)
			(layers "B.Cu" "B.Mask" "B.Paste")
			(roundrect_rratio 0.25)
			(net 1 "GND")
			(pintype "passive")
		)
	)
	(footprint "antmicro-footprints:R_0402_1005Metric"
		(layer "B.Cu")
		(at 126.805 139.802149 90)
		(descr "Resistor SMD 0402")
		(tags "resistor SMD 0402")
		(property "Reference" "R120"
			(at -0.659851 -1.837 90)
			(layer "B.SilkS")
			(effects
				(font
					(size 0.7 0.7)
					(thickness 0.15)
				)
				(justify right bottom mirror)
			)
		)
		(property "Value" "R_2k2_0402"
			(at -1.011843 -1.772047 90)
			(layer "B.Fab")
			(effects
				(font
					(size 0.7 0.7)
					(thickness 0.15)
				)
				(justify right bottom mirror)
			)
		)
		(property "Datasheet" "https://www.bourns.com/docs/product-datasheets/cr.pdf"
			(at 0 0 90)
			(layer "F.Fab")
			(hide yes)
			(effects
				(font
					(size 1.27 1.27)
					(thickness 0.15)
				)
			)
		)
		(property "Manufacturer" "Bourns"
			(at 0 0 90)
			(unlocked yes)
			(layer "B.Fab")
			(hide yes)
			(effects
				(font
					(size 1 1)
					(thickness 0.15)
				)
				(justify mirror)
			)
		)
		(property "MPN" "CR0402-FX-2201GLF"
			(at 0 0 90)
			(unlocked yes)
			(layer "B.Fab")
			(hide yes)
			(effects
				(font
					(size 1 1)
					(thickness 0.15)
				)
				(justify mirror)
			)
		)
		(property "Val" "2k2"
			(at 0 0 90)
			(unlocked yes)
			(layer "B.Fab")
			(hide yes)
			(effects
				(font
					(size 1 1)
					(thickness 0.15)
				)
				(justify mirror)
			)
		)
		(property "License" "Apache-2.0"
			(at 0 0 90)
			(unlocked yes)
			(layer "B.Fab")
			(hide yes)
			(effects
				(font
					(size 1 1)
					(thickness 0.15)
				)
				(justify mirror)
			)
		)
		(property "Author" "Antmicro"
			(at 0 0 90)
			(unlocked yes)
			(layer "B.Fab")
			(hide yes)
			(effects
				(font
					(size 1 1)
					(thickness 0.15)
				)
				(justify mirror)
			)
		)
		(property "Tolerance" "1%"
			(at 0 0 90)
			(unlocked yes)
			(layer "B.Fab")
			(hide yes)
			(effects
				(font
					(size 1 1)
					(thickness 0.15)
				)
				(justify mirror)
			)
		)
		(sheetname "/Ethernet/")
		(sheetfile "ethernet.kicad_sch")
		(attr smd exclude_from_bom dnp)
		(fp_rect
			(start -0.925 0.47)
			(end 0.925 -0.47)
			(stroke
				(width 0.05)
				(type default)
			)
			(fill no)
			(layer "B.CrtYd")
		)
		(fp_rect
			(start -0.5 0.25)
			(end 0.5 -0.25)
			(stroke
				(width 0.15)
				(type solid)
			)
			(fill no)
			(layer "B.Fab")
		)
		(fp_text user "Author: Antmicro"
			(at -0.95 -4.169 270)
			(layer "B.Fab")
			(effects
				(font
					(size 0.7 0.7)
					(thickness 0.15)
				)
				(justify left bottom mirror)
			)
		)
		(fp_text user "${REFERENCE}"
			(at -0.95 -3.168 270)
			(layer "B.Fab")
			(effects
				(font
					(size 0.7 0.7)
					(thickness 0.15)
				)
				(justify left bottom mirror)
			)
		)
		(fp_text user "License: Apache-2.0"
			(at -0.95 -5.169 270)
			(layer "B.Fab")
			(effects
				(font
					(size 0.7 0.7)
					(thickness 0.15)
				)
				(justify left bottom mirror)
			)
		)
		(pad "1" smd roundrect
			(at -0.48 0 90)
			(size 0.59 0.64)
			(layers "B.Cu" "B.Mask" "B.Paste")
			(roundrect_rratio 0.25)
			(net 330 "/Ethernet/LED_SPD")
			(pintype "passive")
		)
		(pad "2" smd roundrect
			(at 0.48 0 90)
			(size 0.59 0.64)
			(layers "B.Cu" "B.Mask" "B.Paste")
			(roundrect_rratio 0.25)
			(net 1 "GND")
			(pintype "passive")
		)
	)
	(footprint "antmicro-footprints:R_0402_1005Metric"
		(layer "B.Cu")
		(at 126.805 144.212149 -90)
		(descr "Resistor SMD 0402")
		(tags "resistor SMD 0402")
		(property "Reference" "R121"
			(at -0.702149 1.837 90)
			(layer "B.SilkS")
			(effects
				(font
					(size 0.7 0.7)
					(thickness 0.15)
				)
				(justify left bottom mirror)
			)
		)
		(property "Value" "R_2k2_0402"
			(at -1.011843 -1.772047 90)
			(layer "B.Fab")
			(effects
				(font
					(size 0.7 0.7)
					(thickness 0.15)
				)
				(justify left bottom mirror)
			)
		)
		(property "Datasheet" "https://www.bourns.com/docs/product-datasheets/cr.pdf"
			(at 0 0 270)
			(layer "F.Fab")
			(hide yes)
			(effects
				(font
					(size 1.27 1.27)
					(thickness 0.15)
				)
			)
		)
		(property "Manufacturer" "Bourns"
			(at 0 0 270)
			(unlocked yes)
			(layer "B.Fab")
			(hide yes)
			(effects
				(font
					(size 1 1)
					(thickness 0.15)
				)
				(justify mirror)
			)
		)
		(property "MPN" "CR0402-FX-2201GLF"
			(at 0 0 270)
			(unlocked yes)
			(layer "B.Fab")
			(hide yes)
			(effects
				(font
					(size 1 1)
					(thickness 0.15)
				)
				(justify mirror)
			)
		)
		(property "Val" "2k2"
			(at 0 0 270)
			(unlocked yes)
			(layer "B.Fab")
			(hide yes)
			(effects
				(font
					(size 1 1)
					(thickness 0.15)
				)
				(justify mirror)
			)
		)
		(property "License" "Apache-2.0"
			(at 0 0 270)
			(unlocked yes)
			(layer "B.Fab")
			(hide yes)
			(effects
				(font
					(size 1 1)
					(thickness 0.15)
				)
				(justify mirror)
			)
		)
		(property "Author" "Antmicro"
			(at 0 0 270)
			(unlocked yes)
			(layer "B.Fab")
			(hide yes)
			(effects
				(font
					(size 1 1)
					(thickness 0.15)
				)
				(justify mirror)
			)
		)
		(property "Tolerance" "1%"
			(at 0 0 270)
			(unlocked yes)
			(layer "B.Fab")
			(hide yes)
			(effects
				(font
					(size 1 1)
					(thickness 0.15)
				)
				(justify mirror)
			)
		)
		(sheetname "/Ethernet/")
		(sheetfile "ethernet.kicad_sch")
		(attr smd exclude_from_bom dnp)
		(fp_rect
			(start -0.925 0.47)
			(end 0.925 -0.47)
			(stroke
				(width 0.05)
				(type default)
			)
			(fill no)
			(layer "B.CrtYd")
		)
		(fp_rect
			(start -0.5 0.25)
			(end 0.5 -0.25)
			(stroke
				(width 0.15)
				(type solid)
			)
			(fill no)
			(layer "B.Fab")
		)
		(fp_text user "Author: Antmicro"
			(at -0.95 -4.169 90)
			(layer "B.Fab")
			(effects
				(font
					(size 0.7 0.7)
					(thickness 0.15)
				)
				(justify left bottom mirror)
			)
		)
		(fp_text user "License: Apache-2.0"
			(at -0.95 -5.169 90)
			(layer "B.Fab")
			(effects
				(font
					(size 0.7 0.7)
					(thickness 0.15)
				)
				(justify left bottom mirror)
			)
		)
		(fp_text user "${REFERENCE}"
			(at -0.95 -3.168 90)
			(layer "B.Fab")
			(effects
				(font
					(size 0.7 0.7)
					(thickness 0.15)
				)
				(justify left bottom mirror)
			)
		)
		(pad "1" smd roundrect
			(at -0.48 0 270)
			(size 0.59 0.64)
			(layers "B.Cu" "B.Mask" "B.Paste")
			(roundrect_rratio 0.25)
			(net 331 "/Ethernet/LED_LINK")
			(pintype "passive")
		)
		(pad "2" smd roundrect
			(at 0.48 0 270)
			(size 0.59 0.64)
			(layers "B.Cu" "B.Mask" "B.Paste")
			(roundrect_rratio 0.25)
			(net 1 "GND")
			(pintype "passive")
		)
	)
	(footprint "antmicro-footprints:R_0402_1005Metric"
		(layer "B.Cu")
		(at 137.5 150.025 90)
		(descr "Resistor SMD 0402")
		(tags "resistor SMD 0402")
		(property "Reference" "R104"
			(at -10.375 0.409 90)
			(layer "B.SilkS")
			(effects
				(font
					(size 0.7 0.7)
					(thickness 0.15)
				)
				(justify right bottom mirror)
			)
		)
		(property "Value" "R_10k_0402"
			(at -1.011843 -1.772047 90)
			(layer "B.Fab")
			(effects
				(font
					(size 0.7 0.7)
					(thickness 0.15)
				)
				(justify right bottom mirror)
			)
		)
		(property "Datasheet" "https://www.bourns.com/docs/product-datasheets/cr.pdf"
			(at 0 0 90)
			(layer "F.Fab")
			(hide yes)
			(effects
				(font
					(size 1.27 1.27)
					(thickness 0.15)
				)
			)
		)
		(property "Manufacturer" "Bourns"
			(at 0 0 90)
			(unlocked yes)
			(layer "B.Fab")
			(hide yes)
			(effects
				(font
					(size 1 1)
					(thickness 0.15)
				)
				(justify mirror)
			)
		)
		(property "MPN" "CR0402-FX-1002GLF"
			(at 0 0 90)
			(unlocked yes)
			(layer "B.Fab")
			(hide yes)
			(effects
				(font
					(size 1 1)
					(thickness 0.15)
				)
				(justify mirror)
			)
		)
		(property "Val" "10k"
			(at 0 0 90)
			(unlocked yes)
			(layer "B.Fab")
			(hide yes)
			(effects
				(font
					(size 1 1)
					(thickness 0.15)
				)
				(justify mirror)
			)
		)
		(property "License" "Apache-2.0"
			(at 0 0 90)
			(unlocked yes)
			(layer "B.Fab")
			(hide yes)
			(effects
				(font
					(size 1 1)
					(thickness 0.15)
				)
				(justify mirror)
			)
		)
		(property "Author" "Antmicro"
			(at 0 0 90)
			(unlocked yes)
			(layer "B.Fab")
			(hide yes)
			(effects
				(font
					(size 1 1)
					(thickness 0.15)
				)
				(justify mirror)
			)
		)
		(property "Tolerance" "1%"
			(at 0 0 90)
			(unlocked yes)
			(layer "B.Fab")
			(hide yes)
			(effects
				(font
					(size 1 1)
					(thickness 0.15)
				)
				(justify mirror)
			)
		)
		(sheetname "/Ethernet/")
		(sheetfile "ethernet.kicad_sch")
		(attr smd)
		(fp_rect
			(start -0.925 0.47)
			(end 0.925 -0.47)
			(stroke
				(width 0.05)
				(type default)
			)
			(fill no)
			(layer "B.CrtYd")
		)
		(fp_rect
			(start -0.5 0.25)
			(end 0.5 -0.25)
			(stroke
				(width 0.15)
				(type solid)
			)
			(fill no)
			(layer "B.Fab")
		)
		(fp_text user "${REFERENCE}"
			(at -0.95 -3.168 270)
			(layer "B.Fab")
			(effects
				(font
					(size 0.7 0.7)
					(thickness 0.15)
				)
				(justify left bottom mirror)
			)
		)
		(fp_text user "Author: Antmicro"
			(at -0.95 -4.169 270)
			(layer "B.Fab")
			(effects
				(font
					(size 0.7 0.7)
					(thickness 0.15)
				)
				(justify left bottom mirror)
			)
		)
		(fp_text user "License: Apache-2.0"
			(at -0.95 -5.169 270)
			(layer "B.Fab")
			(effects
				(font
					(size 0.7 0.7)
					(thickness 0.15)
				)
				(justify left bottom mirror)
			)
		)
		(pad "1" smd roundrect
			(at -0.48 0 90)
			(size 0.59 0.64)
			(layers "B.Cu" "B.Mask" "B.Paste")
			(roundrect_rratio 0.25)
			(net 396 "/Ethernet/ETH.RXD3")
			(pintype "passive")
		)
		(pad "2" smd roundrect
			(at 0.48 0 90)
			(size 0.59 0.64)
			(layers "B.Cu" "B.Mask" "B.Paste")
			(roundrect_rratio 0.25)
			(net 797 "+1V8")
			(pintype "passive")
		)
	)
	(footprint "antmicro-footprints:R_0402_1005Metric"
		(layer "B.Cu")
		(at 137.5 152.4 -90)
		(descr "Resistor SMD 0402")
		(tags "resistor SMD 0402")
		(property "Reference" "R116"
			(at 8 -0.375 90)
			(layer "B.SilkS")
			(effects
				(font
					(size 0.7 0.7)
					(thickness 0.15)
				)
				(justify left bottom mirror)
			)
		)
		(property "Value" "R_2k2_0402"
			(at -1.011843 -1.772047 90)
			(layer "B.Fab")
			(effects
				(font
					(size 0.7 0.7)
					(thickness 0.15)
				)
				(justify left bottom mirror)
			)
		)
		(property "Datasheet" "https://www.bourns.com/docs/product-datasheets/cr.pdf"
			(at 0 0 270)
			(layer "F.Fab")
			(hide yes)
			(effects
				(font
					(size 1.27 1.27)
					(thickness 0.15)
				)
			)
		)
		(property "Manufacturer" "Bourns"
			(at 0 0 270)
			(unlocked yes)
			(layer "B.Fab")
			(hide yes)
			(effects
				(font
					(size 1 1)
					(thickness 0.15)
				)
				(justify mirror)
			)
		)
		(property "MPN" "CR0402-FX-2201GLF"
			(at 0 0 270)
			(unlocked yes)
			(layer "B.Fab")
			(hide yes)
			(effects
				(font
					(size 1 1)
					(thickness 0.15)
				)
				(justify mirror)
			)
		)
		(property "Val" "2k2"
			(at 0 0 270)
			(unlocked yes)
			(layer "B.Fab")
			(hide yes)
			(effects
				(font
					(size 1 1)
					(thickness 0.15)
				)
				(justify mirror)
			)
		)
		(property "License" "Apache-2.0"
			(at 0 0 270)
			(unlocked yes)
			(layer "B.Fab")
			(hide yes)
			(effects
				(font
					(size 1 1)
					(thickness 0.15)
				)
				(justify mirror)
			)
		)
		(property "Author" "Antmicro"
			(at 0 0 270)
			(unlocked yes)
			(layer "B.Fab")
			(hide yes)
			(effects
				(font
					(size 1 1)
					(thickness 0.15)
				)
				(justify mirror)
			)
		)
		(property "Tolerance" "1%"
			(at 0 0 270)
			(unlocked yes)
			(layer "B.Fab")
			(hide yes)
			(effects
				(font
					(size 1 1)
					(thickness 0.15)
				)
				(justify mirror)
			)
		)
		(sheetname "/Ethernet/")
		(sheetfile "ethernet.kicad_sch")
		(attr smd exclude_from_bom dnp)
		(fp_rect
			(start -0.925 0.47)
			(end 0.925 -0.47)
			(stroke
				(width 0.05)
				(type default)
			)
			(fill no)
			(layer "B.CrtYd")
		)
		(fp_rect
			(start -0.5 0.25)
			(end 0.5 -0.25)
			(stroke
				(width 0.15)
				(type solid)
			)
			(fill no)
			(layer "B.Fab")
		)
		(fp_text user "Author: Antmicro"
			(at -0.95 -4.169 90)
			(layer "B.Fab")
			(effects
				(font
					(size 0.7 0.7)
					(thickness 0.15)
				)
				(justify left bottom mirror)
			)
		)
		(fp_text user "License: Apache-2.0"
			(at -0.95 -5.169 90)
			(layer "B.Fab")
			(effects
				(font
					(size 0.7 0.7)
					(thickness 0.15)
				)
				(justify left bottom mirror)
			)
		)
		(fp_text user "${REFERENCE}"
			(at -0.95 -3.168 90)
			(layer "B.Fab")
			(effects
				(font
					(size 0.7 0.7)
					(thickness 0.15)
				)
				(justify left bottom mirror)
			)
		)
		(pad "1" smd roundrect
			(at -0.48 0 270)
			(size 0.59 0.64)
			(layers "B.Cu" "B.Mask" "B.Paste")
			(roundrect_rratio 0.25)
			(net 396 "/Ethernet/ETH.RXD3")
			(pintype "passive")
		)
		(pad "2" smd roundrect
			(at 0.48 0 270)
			(size 0.59 0.64)
			(layers "B.Cu" "B.Mask" "B.Paste")
			(roundrect_rratio 0.25)
			(net 1 "GND")
			(pintype "passive")
		)
	)
)
